(kicad_pcb
	(version 20260206)
	(generator "pcbnew")
	(generator_version "10.0")
	(general
		(thickness 1.6)
		(legacy_teardrops no)
	)
	(paper "A4")
	(title_block
		(title "panther-plus-userver — 13130-1b_20150205.brd")
		(comment 1 "Honey Badger (Wiwynn) / footprints 750-758 of 1509")
	)
	(layers
		(0 "F.Cu" signal "TOP")
		(4 "In1.Cu" signal "L2")
		(6 "In2.Cu" signal "L3")
		(8 "In3.Cu" signal "L4")
		(10 "In4.Cu" signal "L5")
		(12 "In5.Cu" signal "L6")
		(14 "In6.Cu" signal "L7")
		(16 "In7.Cu" signal "L8")
		(18 "In8.Cu" signal "L9")
		(20 "In9.Cu" signal "L10")
		(22 "In10.Cu" signal "L11")
		(2 "B.Cu" signal "BOTTOM")
		(9 "F.Adhes" user "F.Adhesive")
		(11 "B.Adhes" user "B.Adhesive")
		(13 "F.Paste" user "Package Geometry/Pastemask Top")
		(15 "B.Paste" user "Package Geometry/Pastemask Bottom")
		(5 "F.SilkS" user "Ref Des/Silkscreen Top")
		(7 "B.SilkS" user "Ref Des/Silkscreen Bottom")
		(1 "F.Mask" user "Board Geometry/Soldermask Top")
		(3 "B.Mask" user "Board Geometry/Soldermask Bottom")
		(17 "Dwgs.User" user "User.Drawings")
		(19 "Cmts.User" user "User.Comments")
		(21 "Eco1.User" user "User.Eco1")
		(23 "Eco2.User" user "User.Eco2")
		(25 "Edge.Cuts" user "Board Geometry/Outline")
		(27 "Margin" user)
		(31 "F.CrtYd" user "Package Geometry/Place Bound Top")
		(29 "B.CrtYd" user "Package Geometry/Place Bound Bottom")
		(35 "F.Fab" user "Ref Des/Assembly Top")
		(33 "B.Fab" user "Ref Des/Assembly Bottom")
	)
	(footprint ""
		(layer "F.Cu")
		(at 46.1264 -44.704 -90)
		(property "Reference" "C29"
			(at 0 0 270)
			(layer "F.SilkS")
			(hide yes)
			(effects
				(font
					(size 1.27 1.27)
				)
			)
		)
		(property "Value" "SCD1U10V2KX-5GP"
			(at 1.8923 -1.2065 270)
			(unlocked yes)
			(layer "F.Fab")
			(hide yes)
			(effects
				(font
					(size 1.016 1.016)
					(thickness 0.1524)
				)
			)
		)
		(property "Device Type" "C402H22"
			(at 1.8923 -2.7305 270)
			(unlocked yes)
			(layer "F.Fab")
			(hide yes)
			(effects
				(font
					(size 1.016 1.016)
					(thickness 0.1524)
				)
			)
		)
		(duplicate_pad_numbers_are_jumpers no)
		(fp_rect
			(start -0.381 0.7366)
			(end 0.381 -0.7366)
			(stroke
				(width 0)
				(type default)
			)
			(fill no)
			(layer "F.CrtYd")
		)
		(fp_rect
			(start -0.381 0.7366)
			(end 0.381 -0.7366)
			(stroke
				(width 0)
				(type default)
			)
			(fill no)
			(layer "F.Fab")
		)
		(pad "1" smd custom
			(at 0 -0.4572 270)
			(size 0.1143 0.1143)
			(layers "F.Cu" "F.Mask" "F.Paste")
			(net "P3V3_STBY")
			(options
				(clearance outline)
				(anchor circle)
			)
			(primitives
				(gr_poly
					(pts
						(arc
							(start -0.254 -0.1778)
							(mid -0.239121 -0.213721)
							(end -0.2032 -0.2286)
						)
						(arc
							(start 0.2032 -0.2286)
							(mid 0.239121 -0.213721)
							(end 0.254 -0.1778)
						)
						(arc
							(start 0.254 0.1778)
							(mid 0.239121 0.213721)
							(end 0.2032 0.2286)
						)
						(arc
							(start -0.2032 0.2286)
							(mid -0.239121 0.213721)
							(end -0.254 0.1778)
						)
					)
					(width 0)
					(fill yes)
				)
			)
		)
		(pad "2" smd custom
			(at 0 0.4572 270)
			(size 0.1143 0.1143)
			(layers "F.Cu" "F.Mask" "F.Paste")
			(net "GND")
			(options
				(clearance outline)
				(anchor circle)
			)
			(primitives
				(gr_poly
					(pts
						(arc
							(start -0.254 -0.1778)
							(mid -0.239121 -0.213721)
							(end -0.2032 -0.2286)
						)
						(arc
							(start 0.2032 -0.2286)
							(mid 0.239121 -0.213721)
							(end 0.254 -0.1778)
						)
						(arc
							(start 0.254 0.1778)
							(mid 0.239121 0.213721)
							(end 0.2032 0.2286)
						)
						(arc
							(start -0.2032 0.2286)
							(mid -0.239121 0.213721)
							(end -0.254 0.1778)
						)
					)
					(width 0)
					(fill yes)
				)
			)
		)
	)
	(footprint ""
		(layer "F.Cu")
		(at 21.209 -28.829 90)
		(property "Reference" "PL5"
			(at 0 0 90)
			(layer "F.SilkS")
			(hide yes)
			(effects
				(font
					(size 1.27 1.27)
				)
			)
		)
		(property "Value" "COIL-D68UH-9-GP"
			(at -4.522978 -6.630924 90)
			(unlocked yes)
			(layer "F.Fab")
			(hide yes)
			(effects
				(font
					(size 1.016 1.016)
					(thickness 0.1524)
				)
			)
		)
		(property "Device Type" "L7066-1830-UH119"
			(at -4.522978 -8.154924 90)
			(unlocked yes)
			(layer "F.Fab")
			(hide yes)
			(effects
				(font
					(size 1.016 1.016)
					(thickness 0.1524)
				)
			)
		)
		(duplicate_pad_numbers_are_jumpers no)
		(fp_rect
			(start -3.556 4.1148)
			(end 3.556 -4.1148)
			(stroke
				(width 0)
				(type default)
			)
			(fill no)
			(layer "F.CrtYd")
		)
		(fp_rect
			(start -3.556 4.1148)
			(end 3.556 -4.1148)
			(stroke
				(width 0)
				(type default)
			)
			(fill no)
			(layer "F.Fab")
		)
		(pad "1" smd rect
			(at 0 -2.652522 90)
			(size 3.5052 2.667)
			(layers "F.Cu" "F.Mask" "F.Paste")
			(net "P1V0_LX")
		)
		(pad "2" smd rect
			(at 0 2.652522 90)
			(size 3.5052 2.667)
			(layers "F.Cu" "F.Mask" "F.Paste")
			(net "P1V0")
		)
	)
	(footprint ""
		(layer "F.Cu")
		(at 140.589 -50.5968 -90)
		(property "Reference" "R91"
			(at 0 0 270)
			(layer "F.SilkS")
			(hide yes)
			(effects
				(font
					(size 1.27 1.27)
				)
			)
		)
		(property "Value" "4K7R2F-GP"
			(at 1.7907 -1.1176 270)
			(unlocked yes)
			(layer "F.Fab")
			(hide yes)
			(effects
				(font
					(size 1.016 1.016)
					(thickness 0.1524)
				)
			)
		)
		(property "Device Type" "R402H16"
			(at 1.7907 -2.6416 270)
			(unlocked yes)
			(layer "F.Fab")
			(hide yes)
			(effects
				(font
					(size 1.016 1.016)
					(thickness 0.1524)
				)
			)
		)
		(duplicate_pad_numbers_are_jumpers no)
		(fp_rect
			(start -0.381 0.8382)
			(end 0.381 -0.8382)
			(stroke
				(width 0)
				(type default)
			)
			(fill no)
			(layer "F.CrtYd")
		)
		(fp_rect
			(start -0.381 0.8382)
			(end 0.381 -0.8382)
			(stroke
				(width 0)
				(type default)
			)
			(fill no)
			(layer "F.Fab")
		)
		(pad "1" smd custom
			(at 0 -0.4318 270)
			(size 0.127 0.127)
			(layers "F.Cu" "F.Mask" "F.Paste")
			(net "SPI_SW_ADDR2")
			(options
				(clearance outline)
				(anchor circle)
			)
			(primitives
				(gr_poly
					(pts
						(arc
							(start -0.2032 -0.2794)
							(mid -0.239121 -0.264521)
							(end -0.254 -0.2286)
						)
						(arc
							(start -0.254 0.2286)
							(mid -0.239121 0.264521)
							(end -0.2032 0.2794)
						)
						(arc
							(start 0.2032 0.2794)
							(mid 0.239121 0.264521)
							(end 0.254 0.2286)
						)
						(arc
							(start 0.254 -0.2286)
							(mid 0.239121 -0.264521)
							(end 0.2032 -0.2794)
						)
					)
					(width 0)
					(fill yes)
				)
			)
		)
		(pad "2" smd custom
			(at 0 0.4318 270)
			(size 0.127 0.127)
			(layers "F.Cu" "F.Mask" "F.Paste")
			(net "GND")
			(options
				(clearance outline)
				(anchor circle)
			)
			(primitives
				(gr_poly
					(pts
						(arc
							(start -0.2032 -0.2794)
							(mid -0.239121 -0.264521)
							(end -0.254 -0.2286)
						)
						(arc
							(start -0.254 0.2286)
							(mid -0.239121 0.264521)
							(end -0.2032 0.2794)
						)
						(arc
							(start 0.2032 0.2794)
							(mid 0.239121 0.264521)
							(end 0.254 0.2286)
						)
						(arc
							(start 0.254 -0.2286)
							(mid 0.239121 -0.264521)
							(end 0.2032 -0.2794)
						)
					)
					(width 0)
					(fill yes)
				)
			)
		)
	)
	(footprint ""
		(layer "F.Cu")
		(at 169.6974 -12.955778 180)
		(property "Reference" "C373"
			(at 0 0 180)
			(layer "F.SilkS")
			(hide yes)
			(effects
				(font
					(size 1.27 1.27)
				)
			)
		)
		(property "Value" "SC47U6D3V5MX-1-GP"
			(at 0 -4.9022 180)
			(unlocked yes)
			(layer "F.Fab")
			(hide yes)
			(effects
				(font
					(size 1.016 1.016)
					(thickness 0.1524)
				)
			)
		)
		(property "Device Type" "C805H54"
			(at 0 -6.8072 180)
			(unlocked yes)
			(layer "F.Fab")
			(hide yes)
			(effects
				(font
					(size 1.016 1.016)
					(thickness 0.1524)
				)
			)
		)
		(duplicate_pad_numbers_are_jumpers no)
		(fp_line
			(start 0.6096 0)
			(end -0.6096 0)
			(stroke
				(width 0.3048)
				(type default)
			)
			(layer "F.SilkS")
		)
		(fp_poly
			(pts
				(xy -0.9017 1.4351) (xy 0.9017 1.4351) (xy 0.9017 -1.4351) (xy -0.9017 -1.4351)
			)
			(stroke
				(width 0)
				(type default)
			)
			(fill no)
			(layer "F.CrtYd")
		)
		(fp_poly
			(pts
				(xy 0.9017 1.4351) (xy 0.9017 -1.4351) (xy -0.9017 -1.4351) (xy -0.9017 1.4351)
			)
			(stroke
				(width 0)
				(type default)
			)
			(fill no)
			(layer "F.Fab")
		)
		(pad "1" smd rect
			(at 0 -0.8382 180)
			(size 1.5494 0.9398)
			(layers "F.Cu" "F.Mask" "F.Paste")
			(net "PV_VDDR")
		)
		(pad "2" smd rect
			(at 0 0.8382 180)
			(size 1.5494 0.9398)
			(layers "F.Cu" "F.Mask" "F.Paste")
			(net "GND")
		)
	)
	(footprint ""
		(layer "F.Cu")
		(at 18.482818 -63.375286 -90)
		(property "Reference" "PR30"
			(at 0 0 270)
			(layer "F.SilkS")
			(hide yes)
			(effects
				(font
					(size 1.27 1.27)
				)
			)
		)
		(property "Value" "5K1R2F-2-GP"
			(at 1.7907 -1.1176 270)
			(unlocked yes)
			(layer "F.Fab")
			(hide yes)
			(effects
				(font
					(size 1.016 1.016)
					(thickness 0.1524)
				)
			)
		)
		(property "Device Type" "R402H16"
			(at 1.7907 -2.6416 270)
			(unlocked yes)
			(layer "F.Fab")
			(hide yes)
			(effects
				(font
					(size 1.016 1.016)
					(thickness 0.1524)
				)
			)
		)
		(duplicate_pad_numbers_are_jumpers no)
		(fp_rect
			(start -0.381 0.8382)
			(end 0.381 -0.8382)
			(stroke
				(width 0)
				(type default)
			)
			(fill no)
			(layer "F.CrtYd")
		)
		(fp_rect
			(start -0.381 0.8382)
			(end 0.381 -0.8382)
			(stroke
				(width 0)
				(type default)
			)
			(fill no)
			(layer "F.Fab")
		)
		(pad "1" smd custom
			(at 0 -0.4318 270)
			(size 0.127 0.127)
			(layers "F.Cu" "F.Mask" "F.Paste")
			(net "VR_PVNN_COMP")
			(options
				(clearance outline)
				(anchor circle)
			)
			(primitives
				(gr_poly
					(pts
						(arc
							(start -0.2032 -0.2794)
							(mid -0.239121 -0.264521)
							(end -0.254 -0.2286)
						)
						(arc
							(start -0.254 0.2286)
							(mid -0.239121 0.264521)
							(end -0.2032 0.2794)
						)
						(arc
							(start 0.2032 0.2794)
							(mid 0.239121 0.264521)
							(end 0.254 0.2286)
						)
						(arc
							(start 0.254 -0.2286)
							(mid 0.239121 -0.264521)
							(end 0.2032 -0.2794)
						)
					)
					(width 0)
					(fill yes)
				)
			)
		)
		(pad "2" smd custom
			(at 0 0.4318 270)
			(size 0.127 0.127)
			(layers "F.Cu" "F.Mask" "F.Paste")
			(net "VR_PVNN_VW")
			(options
				(clearance outline)
				(anchor circle)
			)
			(primitives
				(gr_poly
					(pts
						(arc
							(start -0.2032 -0.2794)
							(mid -0.239121 -0.264521)
							(end -0.254 -0.2286)
						)
						(arc
							(start -0.254 0.2286)
							(mid -0.239121 0.264521)
							(end -0.2032 0.2794)
						)
						(arc
							(start 0.2032 0.2794)
							(mid 0.239121 0.264521)
							(end 0.254 0.2286)
						)
						(arc
							(start 0.254 -0.2286)
							(mid 0.239121 -0.264521)
							(end 0.2032 -0.2794)
						)
					)
					(width 0)
					(fill yes)
				)
			)
		)
	)
	(footprint ""
		(layer "F.Cu")
		(at 12.9286 -63.6016 90)
		(property "Reference" "PR36"
			(at 0 0 90)
			(layer "F.SilkS")
			(hide yes)
			(effects
				(font
					(size 1.27 1.27)
				)
			)
		)
		(property "Value" "1K91R2F-1-GP"
			(at 1.7907 -1.1176 90)
			(unlocked yes)
			(layer "F.Fab")
			(hide yes)
			(effects
				(font
					(size 1.016 1.016)
					(thickness 0.1524)
				)
			)
		)
		(property "Device Type" "R402H16"
			(at 1.7907 -2.6416 90)
			(unlocked yes)
			(layer "F.Fab")
			(hide yes)
			(effects
				(font
					(size 1.016 1.016)
					(thickness 0.1524)
				)
			)
		)
		(duplicate_pad_numbers_are_jumpers no)
		(fp_rect
			(start -0.381 0.8382)
			(end 0.381 -0.8382)
			(stroke
				(width 0)
				(type default)
			)
			(fill no)
			(layer "F.CrtYd")
		)
		(fp_rect
			(start -0.381 0.8382)
			(end 0.381 -0.8382)
			(stroke
				(width 0)
				(type default)
			)
			(fill no)
			(layer "F.Fab")
		)
		(pad "1" smd custom
			(at 0 -0.4318 90)
			(size 0.127 0.127)
			(layers "F.Cu" "F.Mask" "F.Paste")
			(net "P3V3_STBY")
			(options
				(clearance outline)
				(anchor circle)
			)
			(primitives
				(gr_poly
					(pts
						(arc
							(start -0.2032 -0.2794)
							(mid -0.239121 -0.264521)
							(end -0.254 -0.2286)
						)
						(arc
							(start -0.254 0.2286)
							(mid -0.239121 0.264521)
							(end -0.2032 0.2794)
						)
						(arc
							(start 0.2032 0.2794)
							(mid 0.239121 0.264521)
							(end 0.254 0.2286)
						)
						(arc
							(start 0.254 -0.2286)
							(mid 0.239121 -0.264521)
							(end 0.2032 -0.2794)
						)
					)
					(width 0)
					(fill yes)
				)
			)
		)
		(pad "2" smd custom
			(at 0 0.4318 90)
			(size 0.127 0.127)
			(layers "F.Cu" "F.Mask" "F.Paste")
			(net "PWRGD_PVCCP_VNN_PG")
			(options
				(clearance outline)
				(anchor circle)
			)
			(primitives
				(gr_poly
					(pts
						(arc
							(start -0.2032 -0.2794)
							(mid -0.239121 -0.264521)
							(end -0.254 -0.2286)
						)
						(arc
							(start -0.254 0.2286)
							(mid -0.239121 0.264521)
							(end -0.2032 0.2794)
						)
						(arc
							(start 0.2032 0.2794)
							(mid 0.239121 0.264521)
							(end 0.254 0.2286)
						)
						(arc
							(start 0.254 -0.2286)
							(mid 0.239121 -0.264521)
							(end 0.2032 -0.2794)
						)
					)
					(width 0)
					(fill yes)
				)
			)
		)
	)
	(footprint ""
		(layer "F.Cu")
		(at 18.2372 -43.942 180)
		(property "Reference" "PC176"
			(at 0 0 180)
			(layer "F.SilkS")
			(hide yes)
			(effects
				(font
					(size 1.27 1.27)
				)
			)
		)
		(property "Value" "SC2K2P50V3KX-GP"
			(at -0.0254 -2.0193 180)
			(unlocked yes)
			(layer "F.Fab")
			(hide yes)
			(effects
				(font
					(size 1.016 1.016)
					(thickness 0.1524)
				)
			)
		)
		(property "Device Type" "C603"
			(at -0.0254 -3.5433 180)
			(unlocked yes)
			(layer "F.Fab")
			(hide yes)
			(effects
				(font
					(size 1.016 1.016)
					(thickness 0.1524)
				)
			)
		)
		(duplicate_pad_numbers_are_jumpers no)
		(fp_line
			(start -0.4064 0)
			(end 0.4064 0)
			(stroke
				(width 0.2032)
				(type default)
			)
			(layer "F.SilkS")
		)
		(fp_rect
			(start -0.635 1.1811)
			(end 0.635 -1.1811)
			(stroke
				(width 0)
				(type default)
			)
			(fill no)
			(layer "F.CrtYd")
		)
		(fp_rect
			(start -0.635 1.1811)
			(end 0.635 -1.1811)
			(stroke
				(width 0)
				(type default)
			)
			(fill no)
			(layer "F.Fab")
		)
		(pad "1" smd custom
			(at 0 -0.6604 180)
			(size 0.19685 0.19685)
			(layers "F.Cu" "F.Mask" "F.Paste")
			(net "P3V3_STBY_LL")
			(options
				(clearance outline)
				(anchor circle)
			)
			(primitives
				(gr_poly
					(pts
						(arc
							(start 0.508 -0.2921)
							(mid 0.478242 -0.363942)
							(end 0.4064 -0.3937)
						)
						(arc
							(start -0.4064 -0.3937)
							(mid -0.478242 -0.363942)
							(end -0.508 -0.2921)
						)
						(arc
							(start -0.508 0.2921)
							(mid -0.478242 0.363942)
							(end -0.4064 0.3937)
						)
						(arc
							(start 0.4064 0.3937)
							(mid 0.478242 0.363942)
							(end 0.508 0.2921)
						)
					)
					(width 0)
					(fill yes)
				)
			)
		)
		(pad "2" smd custom
			(at 0 0.6604 180)
			(size 0.19685 0.19685)
			(layers "F.Cu" "F.Mask" "F.Paste")
			(net "P3V3_STBY_SNB")
			(options
				(clearance outline)
				(anchor circle)
			)
			(primitives
				(gr_poly
					(pts
						(arc
							(start 0.508 -0.2921)
							(mid 0.478242 -0.363942)
							(end 0.4064 -0.3937)
						)
						(arc
							(start -0.4064 -0.3937)
							(mid -0.478242 -0.363942)
							(end -0.508 -0.2921)
						)
						(arc
							(start -0.508 0.2921)
							(mid -0.478242 0.363942)
							(end -0.4064 0.3937)
						)
						(arc
							(start 0.4064 0.3937)
							(mid 0.478242 0.363942)
							(end 0.508 0.2921)
						)
					)
					(width 0)
					(fill yes)
				)
			)
		)
	)
	(footprint ""
		(layer "F.Cu")
		(at 140.83792 -58.669428 -90)
		(property "Reference" "PR61"
			(at 0 0 270)
			(layer "F.SilkS")
			(hide yes)
			(effects
				(font
					(size 1.27 1.27)
				)
			)
		)
		(property "Value" "10R3F-GP"
			(at -0.0254 -2.5146 270)
			(unlocked yes)
			(layer "F.Fab")
			(hide yes)
			(effects
				(font
					(size 1.016 1.016)
					(thickness 0.1524)
				)
			)
		)
		(property "Device Type" "R603H22"
			(at -0.0254 -4.0386 270)
			(unlocked yes)
			(layer "F.Fab")
			(hide yes)
			(effects
				(font
					(size 1.016 1.016)
					(thickness 0.1524)
				)
			)
		)
		(duplicate_pad_numbers_are_jumpers no)
		(fp_line
			(start -0.2032 0)
			(end -0.4191 0)
			(stroke
				(width 0.2032)
				(type default)
			)
			(layer "F.SilkS")
		)
		(fp_line
			(start 0.4318 0)
			(end 0.2032 0)
			(stroke
				(width 0.2032)
				(type default)
			)
			(layer "F.SilkS")
		)
		(fp_rect
			(start -0.635 1.1811)
			(end 0.635 -1.1811)
			(stroke
				(width 0)
				(type default)
			)
			(fill no)
			(layer "F.CrtYd")
		)
		(fp_rect
			(start -0.635 1.1811)
			(end 0.635 -1.1811)
			(stroke
				(width 0)
				(type default)
			)
			(fill no)
			(layer "F.Fab")
		)
		(pad "1" smd custom
			(at 0 -0.6604 270)
			(size 0.19685 0.19685)
			(layers "F.Cu" "F.Mask" "F.Paste")
			(net "P3V3_STBY")
			(options
				(clearance outline)
				(anchor circle)
			)
			(primitives
				(gr_poly
					(pts
						(arc
							(start 0.508 -0.2921)
							(mid 0.478242 -0.363942)
							(end 0.4064 -0.3937)
						)
						(arc
							(start -0.4064 -0.3937)
							(mid -0.478242 -0.363942)
							(end -0.508 -0.2921)
						)
						(arc
							(start -0.508 0.2921)
							(mid -0.478242 0.363942)
							(end -0.4064 0.3937)
						)
						(arc
							(start 0.4064 0.3937)
							(mid 0.478242 0.363942)
							(end 0.508 0.2921)
						)
					)
					(width 0)
					(fill yes)
				)
			)
		)
		(pad "2" smd custom
			(at 0 0.6604 270)
			(size 0.19685 0.19685)
			(layers "F.Cu" "F.Mask" "F.Paste")
			(net "PV_VTT_DDR_VIN")
			(options
				(clearance outline)
				(anchor circle)
			)
			(primitives
				(gr_poly
					(pts
						(arc
							(start 0.508 -0.2921)
							(mid 0.478242 -0.363942)
							(end 0.4064 -0.3937)
						)
						(arc
							(start -0.4064 -0.3937)
							(mid -0.478242 -0.363942)
							(end -0.508 -0.2921)
						)
						(arc
							(start -0.508 0.2921)
							(mid -0.478242 0.363942)
							(end -0.4064 0.3937)
						)
						(arc
							(start 0.4064 0.3937)
							(mid 0.478242 0.363942)
							(end 0.508 0.2921)
						)
					)
					(width 0)
					(fill yes)
				)
			)
		)
	)
	(footprint ""
		(layer "F.Cu")
		(at 42.418 -42.926)
		(property "Reference" "R65"
			(at 0 0 0)
			(layer "F.SilkS")
			(hide yes)
			(effects
				(font
					(size 1.27 1.27)
				)
			)
		)
		(property "Value" "33R2F-3-GP"
			(at 1.7907 -1.1176 0)
			(unlocked yes)
			(layer "F.Fab")
			(hide yes)
			(effects
				(font
					(size 1.016 1.016)
					(thickness 0.1524)
				)
			)
		)
		(property "Device Type" "R402H16"
			(at 1.7907 -2.6416 0)
			(unlocked yes)
			(layer "F.Fab")
			(hide yes)
			(effects
				(font
					(size 1.016 1.016)
					(thickness 0.1524)
				)
			)
		)
		(duplicate_pad_numbers_are_jumpers no)
		(fp_rect
			(start -0.381 0.8382)
			(end 0.381 -0.8382)
			(stroke
				(width 0)
				(type default)
			)
			(fill no)
			(layer "F.CrtYd")
		)
		(fp_rect
			(start -0.381 0.8382)
			(end 0.381 -0.8382)
			(stroke
				(width 0)
				(type default)
			)
			(fill no)
			(layer "F.Fab")
		)
		(pad "1" smd custom
			(at 0 -0.4318)
			(size 0.127 0.127)
			(layers "F.Cu" "F.Mask" "F.Paste")
			(net "CLK_GEN_DELAY2_PG")
			(options
				(clearance outline)
				(anchor circle)
			)
			(primitives
				(gr_poly
					(pts
						(arc
							(start -0.2032 -0.2794)
							(mid -0.239121 -0.264521)
							(end -0.254 -0.2286)
						)
						(arc
							(start -0.254 0.2286)
							(mid -0.239121 0.264521)
							(end -0.2032 0.2794)
						)
						(arc
							(start 0.2032 0.2794)
							(mid 0.239121 0.264521)
							(end 0.254 0.2286)
						)
						(arc
							(start 0.254 -0.2286)
							(mid 0.239121 -0.264521)
							(end 0.2032 -0.2794)
						)
					)
					(width 0)
					(fill yes)
				)
			)
		)
		(pad "2" smd custom
			(at 0 0.4318)
			(size 0.127 0.127)
			(layers "F.Cu" "F.Mask" "F.Paste")
			(net "CLK_GEN_PG")
			(options
				(clearance outline)
				(anchor circle)
			)
			(primitives
				(gr_poly
					(pts
						(arc
							(start -0.2032 -0.2794)
							(mid -0.239121 -0.264521)
							(end -0.254 -0.2286)
						)
						(arc
							(start -0.254 0.2286)
							(mid -0.239121 0.264521)
							(end -0.2032 0.2794)
						)
						(arc
							(start 0.2032 0.2794)
							(mid 0.239121 0.264521)
							(end 0.254 0.2286)
						)
						(arc
							(start 0.254 -0.2286)
							(mid 0.239121 -0.264521)
							(end 0.2032 -0.2794)
						)
					)
					(width 0)
					(fill yes)
				)
			)
		)
	)
)
